(kicad_pcb
	(version 20260206)
	(generator "pcbnew")
	(generator_version "10.0")
	(general
		(thickness 1.6)
		(legacy_teardrops no)
	)
	(paper "A4")
	(title_block
		(title "Wiwynn_Tioga_Pass_MB.brd")
		(comment 1 "Tioga Pass / footprints 1584-1590 of 4770")
	)
	(layers
		(0 "F.Cu" signal "TOP")
		(4 "In1.Cu" signal "L2GND")
		(6 "In2.Cu" signal "L3")
		(8 "In3.Cu" signal "L4GND")
		(10 "In4.Cu" signal "L5")
		(12 "In5.Cu" signal "L6GND")
		(14 "In6.Cu" signal "L7VCC")
		(16 "In7.Cu" signal "L8VCC")
		(18 "In8.Cu" signal "L9GND")
		(20 "In9.Cu" signal "L10")
		(22 "In10.Cu" signal "L11GND")
		(24 "In11.Cu" signal "L12")
		(26 "In12.Cu" signal "L13GND")
		(2 "B.Cu" signal "BOTTOM")
		(9 "F.Adhes" user "F.Adhesive")
		(11 "B.Adhes" user "B.Adhesive")
		(13 "F.Paste" user "Package Geometry/Pastemask Top")
		(15 "B.Paste" user "Package Geometry/Pastemask Bottom")
		(5 "F.SilkS" user "Ref Des/Silkscreen Top")
		(7 "B.SilkS" user "Ref Des/Silkscreen Bottom")
		(1 "F.Mask" user "Board Geometry/Soldermask Top")
		(3 "B.Mask" user "Board Geometry/Soldermask Bottom")
		(17 "Dwgs.User" user "User.Drawings")
		(19 "Cmts.User" user "User.Comments")
		(21 "Eco1.User" user "User.Eco1")
		(23 "Eco2.User" user "User.Eco2")
		(25 "Edge.Cuts" user "Board Geometry/Outline")
		(27 "Margin" user)
		(31 "F.CrtYd" user "Package Geometry/Place Bound Top")
		(29 "B.CrtYd" user "Package Geometry/Place Bound Bottom")
		(35 "F.Fab" user "Ref Des/Assembly Top")
		(33 "B.Fab" user "Ref Des/Assembly Bottom")
	)
	(footprint ""
		(layer "F.Cu")
		(at 20.447 -70.866)
		(property "Reference" "R1D42"
			(at 0 0 0)
			(layer "F.SilkS")
			(hide yes)
			(effects
				(font
					(size 1.27 1.27)
				)
			)
		)
		(property "Value" ""
			(at 0 0 0)
			(layer "F.Fab")
			(effects
				(font
					(size 1.27 1.27)
				)
			)
		)
		(duplicate_pad_numbers_are_jumpers no)
		(fp_rect
			(start 0.2794 0.9906)
			(end -0.2794 -0.1016)
			(stroke
				(width 0)
				(type default)
			)
			(fill no)
			(layer "F.CrtYd")
		)
		(fp_line
			(start -0.2794 -0.1016)
			(end -0.2794 0.9906)
			(stroke
				(width 0.1)
				(type default)
			)
			(layer "F.Fab")
		)
		(fp_line
			(start -0.2794 0.9906)
			(end 0.2794 0.9906)
			(stroke
				(width 0.1)
				(type default)
			)
			(layer "F.Fab")
		)
		(fp_line
			(start 0.2794 -0.1016)
			(end -0.2794 -0.1016)
			(stroke
				(width 0.1)
				(type default)
			)
			(layer "F.Fab")
		)
		(fp_line
			(start 0.2794 0.9906)
			(end 0.2794 -0.1016)
			(stroke
				(width 0.1)
				(type default)
			)
			(layer "F.Fab")
		)
		(pad "1" smd rect
			(at 0 0)
			(size 0.508 0.508)
			(layers "F.Cu" "F.Mask" "F.Paste")
			(net "A_HSC_UV")
		)
		(pad "2" smd rect
			(at 0 0.889)
			(size 0.508 0.508)
			(layers "F.Cu" "F.Mask" "F.Paste")
			(net "AGND_HSC")
		)
		(zone
			(layer "F.Cu")
			(hatch none 0.5)
			(connect_pads
				(clearance 0)
			)
			(min_thickness 0.25)
			(keepout
				(tracks allowed)
				(vias not_allowed)
				(pads allowed)
				(copperpour not_allowed)
				(footprints allowed)
			)
			(placement
				(enabled no)
				(sheetname "")
			)
			(fill
				(thermal_gap 0.5)
				(thermal_bridge_width 0.5)
				(island_removal_mode 0)
			)
			(polygon
				(pts
					(xy 20.701 -70.231) (xy 20.701 -70.612) (xy 20.193 -70.612) (xy 20.193 -70.231)
				)
			)
		)
		(zone
			(layer "F.Cu")
			(hatch none 0.5)
			(connect_pads
				(clearance 0)
			)
			(min_thickness 0.25)
			(keepout
				(tracks not_allowed)
				(vias allowed)
				(pads allowed)
				(copperpour not_allowed)
				(footprints allowed)
			)
			(placement
				(enabled no)
				(sheetname "")
			)
			(fill
				(thermal_gap 0.5)
				(thermal_bridge_width 0.5)
				(island_removal_mode 0)
			)
			(polygon
				(pts
					(xy 20.701 -70.231) (xy 20.701 -70.612) (xy 20.193 -70.612) (xy 20.193 -70.231)
				)
			)
		)
	)
	(footprint ""
		(layer "F.Cu")
		(at 372.5672 -155.432506 180)
		(property "Reference" "C7A6"
			(at 0 0 180)
			(layer "F.SilkS")
			(hide yes)
			(effects
				(font
					(size 1.27 1.27)
				)
			)
		)
		(property "Value" ""
			(at 0 0 180)
			(layer "F.Fab")
			(effects
				(font
					(size 1.27 1.27)
				)
			)
		)
		(duplicate_pad_numbers_are_jumpers no)
		(fp_poly
			(pts
				(xy 0.3048 -0.1016) (xy 0.3048 0.9906) (xy -0.3048 0.9906) (xy -0.3048 -0.1016)
			)
			(stroke
				(width 0)
				(type default)
			)
			(fill no)
			(layer "F.CrtYd")
		)
		(fp_line
			(start 0.3048 0.9906)
			(end 0.3048 -0.1016)
			(stroke
				(width 0.1)
				(type default)
			)
			(layer "F.Fab")
		)
		(fp_line
			(start 0.3048 -0.1016)
			(end -0.3048 -0.1016)
			(stroke
				(width 0.1)
				(type default)
			)
			(layer "F.Fab")
		)
		(fp_line
			(start -0.3048 0.9906)
			(end 0.3048 0.9906)
			(stroke
				(width 0.1)
				(type default)
			)
			(layer "F.Fab")
		)
		(fp_line
			(start -0.3048 -0.1016)
			(end -0.3048 0.9906)
			(stroke
				(width 0.1)
				(type default)
			)
			(layer "F.Fab")
		)
		(pad "1" smd rect
			(at 0 0 180)
			(size 0.508 0.508)
			(layers "F.Cu" "F.Mask" "F.Paste")
			(net "VR_PVNN_PCH_PH1_VCIN")
		)
		(pad "2" smd rect
			(at 0 0.889 180)
			(size 0.508 0.508)
			(layers "F.Cu" "F.Mask" "F.Paste")
			(net "GND")
		)
		(zone
			(layer "F.Cu")
			(hatch none 0.5)
			(connect_pads
				(clearance 0)
			)
			(min_thickness 0.25)
			(keepout
				(tracks not_allowed)
				(vias allowed)
				(pads allowed)
				(copperpour not_allowed)
				(footprints allowed)
			)
			(placement
				(enabled no)
				(sheetname "")
			)
			(fill
				(thermal_gap 0.5)
				(thermal_bridge_width 0.5)
				(island_removal_mode 0)
			)
			(polygon
				(pts
					(xy 372.8212 -156.067506) (xy 372.3132 -156.067506) (xy 372.3132 -155.686506) (xy 372.8212 -155.686506)
				)
			)
		)
		(zone
			(layer "F.Cu")
			(hatch none 0.5)
			(connect_pads
				(clearance 0)
			)
			(min_thickness 0.25)
			(keepout
				(tracks allowed)
				(vias not_allowed)
				(pads allowed)
				(copperpour not_allowed)
				(footprints allowed)
			)
			(placement
				(enabled no)
				(sheetname "")
			)
			(fill
				(thermal_gap 0.5)
				(thermal_bridge_width 0.5)
				(island_removal_mode 0)
			)
			(polygon
				(pts
					(xy 372.8212 -155.686506) (xy 372.3132 -155.686506) (xy 372.3132 -156.067506) (xy 372.8212 -156.067506)
				)
			)
		)
	)
	(footprint ""
		(layer "F.Cu")
		(at 13.4366 -72.009 180)
		(property "Reference" "R1D41"
			(at 0 0 180)
			(layer "F.SilkS")
			(hide yes)
			(effects
				(font
					(size 1.27 1.27)
				)
			)
		)
		(property "Value" ""
			(at 0 0 180)
			(layer "F.Fab")
			(effects
				(font
					(size 1.27 1.27)
				)
			)
		)
		(duplicate_pad_numbers_are_jumpers no)
		(fp_poly
			(pts
				(xy -0.7239 -0.2159) (xy 0.7239 -0.2159) (xy 0.7239 1.9939) (xy -0.7239 1.9939)
			)
			(stroke
				(width 0)
				(type default)
			)
			(fill no)
			(layer "F.CrtYd")
		)
		(fp_line
			(start 0.7239 1.9939)
			(end 0.7239 -0.2159)
			(stroke
				(width 0.1)
				(type default)
			)
			(layer "F.Fab")
		)
		(fp_line
			(start 0.7239 -0.2159)
			(end -0.7239 -0.2159)
			(stroke
				(width 0.1)
				(type default)
			)
			(layer "F.Fab")
		)
		(fp_line
			(start -0.7239 1.9939)
			(end 0.7239 1.9939)
			(stroke
				(width 0.1)
				(type default)
			)
			(layer "F.Fab")
		)
		(fp_line
			(start -0.7239 -0.2159)
			(end -0.7239 1.9939)
			(stroke
				(width 0.1)
				(type default)
			)
			(layer "F.Fab")
		)
		(pad "1" smd rect
			(at 0 0 180)
			(size 1.27 1.016)
			(layers "F.Cu" "F.Mask" "F.Paste")
			(net "GND")
		)
		(pad "2" smd rect
			(at 0 1.778 180)
			(size 1.27 1.016)
			(layers "F.Cu" "F.Mask" "F.Paste")
			(net "AGND_HSC")
		)
		(zone
			(layer "F.Cu")
			(hatch none 0.5)
			(connect_pads
				(clearance 0)
			)
			(min_thickness 0.25)
			(keepout
				(tracks not_allowed)
				(vias allowed)
				(pads allowed)
				(copperpour not_allowed)
				(footprints allowed)
			)
			(placement
				(enabled no)
				(sheetname "")
			)
			(fill
				(thermal_gap 0.5)
				(thermal_bridge_width 0.5)
				(island_removal_mode 0)
			)
			(polygon
				(pts
					(xy 12.8016 -72.517) (xy 12.8016 -73.279) (xy 12.8905 -73.279) (xy 14.0716 -73.279) (xy 14.0716 -72.517)
				)
			)
		)
	)
	(footprint ""
		(layer "F.Cu")
		(at 433.9336 -16.0528 -90)
		(property "Reference" "R6W44"
			(at -0.8382 -0.67818 270)
			(unlocked yes)
			(layer "F.SilkS")
			(effects
				(font
					(size 0.4064 0.254)
					(thickness 0.1524)
				)
				(justify left)
			)
		)
		(property "Value" ""
			(at 0 0 270)
			(layer "F.Fab")
			(effects
				(font
					(size 1.27 1.27)
				)
			)
		)
		(duplicate_pad_numbers_are_jumpers no)
		(fp_poly
			(pts
				(xy -0.2794 -0.1016) (xy 0.2794 -0.1016) (xy 0.2794 0.9906) (xy -0.2794 0.9906)
			)
			(stroke
				(width 0)
				(type default)
			)
			(fill no)
			(layer "F.CrtYd")
		)
		(fp_line
			(start -0.2794 0.9906)
			(end 0.2794 0.9906)
			(stroke
				(width 0.1)
				(type default)
			)
			(layer "F.Fab")
		)
		(fp_line
			(start 0.2794 0.9906)
			(end 0.2794 -0.1016)
			(stroke
				(width 0.1)
				(type default)
			)
			(layer "F.Fab")
		)
		(fp_line
			(start -0.2794 -0.1016)
			(end -0.2794 0.9906)
			(stroke
				(width 0.1)
				(type default)
			)
			(layer "F.Fab")
		)
		(fp_line
			(start 0.2794 -0.1016)
			(end -0.2794 -0.1016)
			(stroke
				(width 0.1)
				(type default)
			)
			(layer "F.Fab")
		)
		(pad "1" smd rect
			(at 0 0 270)
			(size 0.508 0.508)
			(layers "F.Cu" "F.Mask" "F.Paste")
			(net "P3V3_STBY")
		)
		(pad "2" smd rect
			(at 0 0.889 270)
			(size 0.508 0.508)
			(layers "F.Cu" "F.Mask" "F.Paste")
			(net "PCA9554_A0")
		)
		(zone
			(layer "F.Cu")
			(hatch none 0.5)
			(connect_pads
				(clearance 0)
			)
			(min_thickness 0.25)
			(keepout
				(tracks not_allowed)
				(vias allowed)
				(pads allowed)
				(copperpour not_allowed)
				(footprints allowed)
			)
			(placement
				(enabled no)
				(sheetname "")
			)
			(fill
				(thermal_gap 0.5)
				(thermal_bridge_width 0.5)
				(island_removal_mode 0)
			)
			(polygon
				(pts
					(xy 433.2986 -16.3068) (xy 433.2986 -15.7988) (xy 433.6796 -15.7988) (xy 433.6796 -16.3068)
				)
			)
		)
		(zone
			(layer "F.Cu")
			(hatch none 0.5)
			(connect_pads
				(clearance 0)
			)
			(min_thickness 0.25)
			(keepout
				(tracks allowed)
				(vias not_allowed)
				(pads allowed)
				(copperpour not_allowed)
				(footprints allowed)
			)
			(placement
				(enabled no)
				(sheetname "")
			)
			(fill
				(thermal_gap 0.5)
				(thermal_bridge_width 0.5)
				(island_removal_mode 0)
			)
			(polygon
				(pts
					(xy 433.6796 -16.3068) (xy 433.6796 -15.7988) (xy 433.2986 -15.7988) (xy 433.2986 -16.3068)
				)
			)
		)
	)
	(footprint ""
		(layer "F.Cu")
		(at 407.73604 -112.32642 90)
		(property "Reference" "R7W17"
			(at -0.8382 -0.67818 90)
			(unlocked yes)
			(layer "F.SilkS")
			(effects
				(font
					(size 0.4064 0.254)
					(thickness 0.1524)
				)
				(justify left)
			)
		)
		(property "Value" ""
			(at 0 0 90)
			(layer "F.Fab")
			(effects
				(font
					(size 1.27 1.27)
				)
			)
		)
		(duplicate_pad_numbers_are_jumpers no)
		(fp_poly
			(pts
				(xy -0.2794 -0.1016) (xy 0.2794 -0.1016) (xy 0.2794 0.9906) (xy -0.2794 0.9906)
			)
			(stroke
				(width 0)
				(type default)
			)
			(fill no)
			(layer "F.CrtYd")
		)
		(fp_line
			(start 0.2794 -0.1016)
			(end -0.2794 -0.1016)
			(stroke
				(width 0.1)
				(type default)
			)
			(layer "F.Fab")
		)
		(fp_line
			(start -0.2794 -0.1016)
			(end -0.2794 0.9906)
			(stroke
				(width 0.1)
				(type default)
			)
			(layer "F.Fab")
		)
		(fp_line
			(start 0.2794 0.9906)
			(end 0.2794 -0.1016)
			(stroke
				(width 0.1)
				(type default)
			)
			(layer "F.Fab")
		)
		(fp_line
			(start -0.2794 0.9906)
			(end 0.2794 0.9906)
			(stroke
				(width 0.1)
				(type default)
			)
			(layer "F.Fab")
		)
		(pad "1" smd rect
			(at 0 0 90)
			(size 0.508 0.508)
			(layers "F.Cu" "F.Mask" "F.Paste")
			(net "FM_THROTTLE_R2_N")
		)
		(pad "2" smd rect
			(at 0 0.889 90)
			(size 0.508 0.508)
			(layers "F.Cu" "F.Mask" "F.Paste")
			(net "FM_THROTTLE_N")
		)
		(zone
			(layer "F.Cu")
			(hatch none 0.5)
			(connect_pads
				(clearance 0)
			)
			(min_thickness 0.25)
			(keepout
				(tracks allowed)
				(vias not_allowed)
				(pads allowed)
				(copperpour not_allowed)
				(footprints allowed)
			)
			(placement
				(enabled no)
				(sheetname "")
			)
			(fill
				(thermal_gap 0.5)
				(thermal_bridge_width 0.5)
				(island_removal_mode 0)
			)
			(polygon
				(pts
					(xy 407.99004 -112.07242) (xy 407.99004 -112.58042) (xy 408.37104 -112.58042) (xy 408.37104 -112.07242)
				)
			)
		)
		(zone
			(layer "F.Cu")
			(hatch none 0.5)
			(connect_pads
				(clearance 0)
			)
			(min_thickness 0.25)
			(keepout
				(tracks not_allowed)
				(vias allowed)
				(pads allowed)
				(copperpour not_allowed)
				(footprints allowed)
			)
			(placement
				(enabled no)
				(sheetname "")
			)
			(fill
				(thermal_gap 0.5)
				(thermal_bridge_width 0.5)
				(island_removal_mode 0)
			)
			(polygon
				(pts
					(xy 408.37104 -112.07242) (xy 408.37104 -112.58042) (xy 407.99004 -112.58042) (xy 407.99004 -112.07242)
				)
			)
		)
	)
	(footprint ""
		(layer "F.Cu")
		(at 28.242006 -22.941534)
		(property "Reference" "R1F4"
			(at 0 0 0)
			(layer "F.SilkS")
			(hide yes)
			(effects
				(font
					(size 1.27 1.27)
				)
			)
		)
		(property "Value" ""
			(at 0 0 0)
			(layer "F.Fab")
			(effects
				(font
					(size 1.27 1.27)
				)
			)
		)
		(duplicate_pad_numbers_are_jumpers no)
		(fp_poly
			(pts
				(xy -0.2794 -0.1016) (xy 0.2794 -0.1016) (xy 0.2794 0.9906) (xy -0.2794 0.9906)
			)
			(stroke
				(width 0)
				(type default)
			)
			(fill no)
			(layer "F.CrtYd")
		)
		(fp_line
			(start -0.2794 -0.1016)
			(end -0.2794 0.9906)
			(stroke
				(width 0.1)
				(type default)
			)
			(layer "F.Fab")
		)
		(fp_line
			(start -0.2794 0.9906)
			(end 0.2794 0.9906)
			(stroke
				(width 0.1)
				(type default)
			)
			(layer "F.Fab")
		)
		(fp_line
			(start 0.2794 -0.1016)
			(end -0.2794 -0.1016)
			(stroke
				(width 0.1)
				(type default)
			)
			(layer "F.Fab")
		)
		(fp_line
			(start 0.2794 0.9906)
			(end 0.2794 -0.1016)
			(stroke
				(width 0.1)
				(type default)
			)
			(layer "F.Fab")
		)
		(pad "1" smd rect
			(at 0 0)
			(size 0.508 0.508)
			(layers "F.Cu" "F.Mask" "F.Paste")
			(net "M_G_CPU_VREF")
		)
		(pad "2" smd rect
			(at 0 0.889)
			(size 0.508 0.508)
			(layers "F.Cu" "F.Mask" "F.Paste")
			(net "M_G_VREF")
		)
		(zone
			(layer "F.Cu")
			(hatch none 0.5)
			(connect_pads
				(clearance 0)
			)
			(min_thickness 0.25)
			(keepout
				(tracks allowed)
				(vias not_allowed)
				(pads allowed)
				(copperpour not_allowed)
				(footprints allowed)
			)
			(placement
				(enabled no)
				(sheetname "")
			)
			(fill
				(thermal_gap 0.5)
				(thermal_bridge_width 0.5)
				(island_removal_mode 0)
			)
			(polygon
				(pts
					(xy 27.988006 -22.687534) (xy 28.496006 -22.687534) (xy 28.496006 -22.306534) (xy 27.988006 -22.306534)
				)
			)
		)
		(zone
			(layer "F.Cu")
			(hatch none 0.5)
			(connect_pads
				(clearance 0)
			)
			(min_thickness 0.25)
			(keepout
				(tracks not_allowed)
				(vias allowed)
				(pads allowed)
				(copperpour not_allowed)
				(footprints allowed)
			)
			(placement
				(enabled no)
				(sheetname "")
			)
			(fill
				(thermal_gap 0.5)
				(thermal_bridge_width 0.5)
				(island_removal_mode 0)
			)
			(polygon
				(pts
					(xy 27.988006 -22.306534) (xy 28.496006 -22.306534) (xy 28.496006 -22.687534) (xy 27.988006 -22.687534)
				)
			)
		)
	)
	(footprint ""
		(layer "F.Cu")
		(at 406.7302 -104.648 -90)
		(property "Reference" "R2N9"
			(at 0 0 270)
			(layer "F.SilkS")
			(hide yes)
			(effects
				(font
					(size 1.27 1.27)
				)
			)
		)
		(property "Value" ""
			(at 0 0 270)
			(layer "F.Fab")
			(effects
				(font
					(size 1.27 1.27)
				)
			)
		)
		(duplicate_pad_numbers_are_jumpers no)
		(fp_poly
			(pts
				(xy -0.2794 -0.1016) (xy 0.2794 -0.1016) (xy 0.2794 0.9906) (xy -0.2794 0.9906)
			)
			(stroke
				(width 0)
				(type default)
			)
			(fill no)
			(layer "F.CrtYd")
		)
		(fp_line
			(start -0.2794 0.9906)
			(end 0.2794 0.9906)
			(stroke
				(width 0.1)
				(type default)
			)
			(layer "F.Fab")
		)
		(fp_line
			(start 0.2794 0.9906)
			(end 0.2794 -0.1016)
			(stroke
				(width 0.1)
				(type default)
			)
			(layer "F.Fab")
		)
		(fp_line
			(start -0.2794 -0.1016)
			(end -0.2794 0.9906)
			(stroke
				(width 0.1)
				(type default)
			)
			(layer "F.Fab")
		)
		(fp_line
			(start 0.2794 -0.1016)
			(end -0.2794 -0.1016)
			(stroke
				(width 0.1)
				(type default)
			)
			(layer "F.Fab")
		)
		(pad "1" smd rect
			(at 0 0 270)
			(size 0.508 0.508)
			(layers "F.Cu" "F.Mask" "F.Paste")
			(net "P3V3_STBY")
		)
		(pad "2" smd rect
			(at 0 0.889 270)
			(size 0.508 0.508)
			(layers "F.Cu" "F.Mask" "F.Paste")
			(net "PU_10GBE_LOM_PCI_DISABLE_N")
		)
		(zone
			(layer "F.Cu")
			(hatch none 0.5)
			(connect_pads
				(clearance 0)
			)
			(min_thickness 0.25)
			(keepout
				(tracks not_allowed)
				(vias allowed)
				(pads allowed)
				(copperpour not_allowed)
				(footprints allowed)
			)
			(placement
				(enabled no)
				(sheetname "")
			)
			(fill
				(thermal_gap 0.5)
				(thermal_bridge_width 0.5)
				(island_removal_mode 0)
			)
			(polygon
				(pts
					(xy 406.0952 -104.902) (xy 406.0952 -104.394) (xy 406.4762 -104.394) (xy 406.4762 -104.902)
				)
			)
		)
		(zone
			(layer "F.Cu")
			(hatch none 0.5)
			(connect_pads
				(clearance 0)
			)
			(min_thickness 0.25)
			(keepout
				(tracks allowed)
				(vias not_allowed)
				(pads allowed)
				(copperpour not_allowed)
				(footprints allowed)
			)
			(placement
				(enabled no)
				(sheetname "")
			)
			(fill
				(thermal_gap 0.5)
				(thermal_bridge_width 0.5)
				(island_removal_mode 0)
			)
			(polygon
				(pts
					(xy 406.4762 -104.902) (xy 406.4762 -104.394) (xy 406.0952 -104.394) (xy 406.0952 -104.902)
				)
			)
		)
	)
)
